(kicad_pcb
	(version 20260206)
	(generator "pcbnew")
	(generator_version "10.0")
	(general
		(thickness 1.6)
		(legacy_teardrops no)
	)
	(paper "A4")
	(title_block
		(title "03242023_DA0F0TMBIJ0_F0T_Motherboard_J_brd_V01_OCP.brd")
		(comment 1 "Grand Teton / footprints 2275-2280 of 6105")
	)
	(layers
		(0 "F.Cu" signal "TOP")
		(4 "In1.Cu" signal "GND")
		(6 "In2.Cu" signal "IN1")
		(8 "In3.Cu" signal "GND1")
		(10 "In4.Cu" signal "IN2")
		(12 "In5.Cu" signal "GND2")
		(14 "In6.Cu" signal "IN3")
		(16 "In7.Cu" signal "GND3")
		(18 "In8.Cu" signal "VCC")
		(20 "In9.Cu" signal "VCC1")
		(22 "In10.Cu" signal "GND4")
		(24 "In11.Cu" signal "IN4")
		(26 "In12.Cu" signal "GND5")
		(28 "In13.Cu" signal "IN5")
		(30 "In14.Cu" signal "GND6")
		(32 "In15.Cu" signal "IN6")
		(34 "In16.Cu" signal "GND7")
		(2 "B.Cu" signal "BOTTOM")
		(9 "F.Adhes" user "F.Adhesive")
		(11 "B.Adhes" user "B.Adhesive")
		(13 "F.Paste" user "Package Geometry/Pastemask Top")
		(15 "B.Paste" user "Package Geometry/Pastemask Bottom")
		(5 "F.SilkS" user "Ref Des/Silkscreen Top")
		(7 "B.SilkS" user "Ref Des/Silkscreen Bottom")
		(1 "F.Mask" user "Board Geometry/Soldermask Top")
		(3 "B.Mask" user "Board Geometry/Soldermask Bottom")
		(17 "Dwgs.User" user "User.Drawings")
		(19 "Cmts.User" user "User.Comments")
		(21 "Eco1.User" user "User.Eco1")
		(23 "Eco2.User" user "User.Eco2")
		(25 "Edge.Cuts" user "Board Geometry/Outline")
		(27 "Margin" user)
		(31 "F.CrtYd" user "Package Geometry/Place Bound Top")
		(29 "B.CrtYd" user "Package Geometry/Place Bound Bottom")
		(35 "F.Fab" user "Ref Des/Assembly Top")
		(33 "B.Fab" user "Ref Des/Assembly Bottom")
	)
	(footprint ""
		(layer "F.Cu")
		(at 54.242716 -116.134388 180)
		(property "Reference" "R3707"
			(at 0 0 180)
			(layer "F.SilkS")
			(hide yes)
			(effects
				(font
					(size 1.27 1.27)
				)
			)
		)
		(property "Value" ""
			(at 0 0 180)
			(layer "F.Fab")
			(effects
				(font
					(size 1.27 1.27)
				)
			)
		)
		(duplicate_pad_numbers_are_jumpers no)
		(fp_line
			(start 0.7874 0.4064)
			(end -0.7874 0.4064)
			(stroke
				(width 0.1524)
				(type default)
			)
			(layer "F.SilkS")
		)
		(fp_line
			(start 0.7874 -0.4064)
			(end 0.7874 0.4064)
			(stroke
				(width 0.1524)
				(type default)
			)
			(layer "F.SilkS")
		)
		(fp_line
			(start -0.7874 0.4064)
			(end -0.7874 -0.4064)
			(stroke
				(width 0.1524)
				(type default)
			)
			(layer "F.SilkS")
		)
		(fp_line
			(start -0.7874 -0.4064)
			(end 0.7874 -0.4064)
			(stroke
				(width 0.1524)
				(type default)
			)
			(layer "F.SilkS")
		)
		(fp_line
			(start 0.67945 0.3048)
			(end 0.120396 0.3048)
			(stroke
				(width 0.1)
				(type default)
			)
			(layer "F.Fab")
		)
		(fp_line
			(start 0.67945 -0.3048)
			(end 0.67945 0.3048)
			(stroke
				(width 0.1)
				(type default)
			)
			(layer "F.Fab")
		)
		(fp_line
			(start 0.12065 -0.2794)
			(end 0.12065 -0.3048)
			(stroke
				(width 0.1)
				(type default)
			)
			(layer "F.Fab")
		)
		(fp_line
			(start 0.12065 -0.3048)
			(end 0.67945 -0.3048)
			(stroke
				(width 0.1)
				(type default)
			)
			(layer "F.Fab")
		)
		(fp_line
			(start 0.120396 0.3048)
			(end 0.120396 0.2794)
			(stroke
				(width 0.1)
				(type default)
			)
			(layer "F.Fab")
		)
		(fp_line
			(start 0.120396 0.2794)
			(end -0.12065 0.2794)
			(stroke
				(width 0.1)
				(type default)
			)
			(layer "F.Fab")
		)
		(fp_line
			(start -0.12065 0.3048)
			(end -0.67945 0.3048)
			(stroke
				(width 0.1)
				(type default)
			)
			(layer "F.Fab")
		)
		(fp_line
			(start -0.12065 0.2794)
			(end -0.12065 0.3048)
			(stroke
				(width 0.1)
				(type default)
			)
			(layer "F.Fab")
		)
		(fp_line
			(start -0.12065 -0.2794)
			(end 0.12065 -0.2794)
			(stroke
				(width 0.1)
				(type default)
			)
			(layer "F.Fab")
		)
		(fp_line
			(start -0.12065 -0.305054)
			(end -0.12065 -0.2794)
			(stroke
				(width 0.1)
				(type default)
			)
			(layer "F.Fab")
		)
		(fp_line
			(start -0.67945 0.3048)
			(end -0.67945 -0.305054)
			(stroke
				(width 0.1)
				(type default)
			)
			(layer "F.Fab")
		)
		(fp_line
			(start -0.67945 -0.305054)
			(end -0.12065 -0.305054)
			(stroke
				(width 0.1)
				(type default)
			)
			(layer "F.Fab")
		)
		(pad "1" smd circle
			(at -0.40005 0 180)
			(size 0 0)
			(layers "F.Cu" "F.Mask" "F.Paste")
			(net "PCA9548_PCIE0_ADDR1")
		)
		(pad "2" smd circle
			(at 0.40005 0 180)
			(size 0 0)
			(layers "F.Cu" "F.Mask" "F.Paste")
			(net "GND")
		)
	)
	(footprint ""
		(layer "F.Cu")
		(at 185.806842 -24.170132)
		(property "Reference" "PC2234"
			(at 0 0 0)
			(layer "F.SilkS")
			(hide yes)
			(effects
				(font
					(size 1.27 1.27)
				)
			)
		)
		(property "Value" ""
			(at 0 0 0)
			(layer "F.Fab")
			(effects
				(font
					(size 1.27 1.27)
				)
			)
		)
		(duplicate_pad_numbers_are_jumpers no)
		(fp_line
			(start -0.7874 -0.4064)
			(end 0.7874 -0.4064)
			(stroke
				(width 0.1524)
				(type default)
			)
			(layer "F.SilkS")
		)
		(fp_line
			(start -0.7874 0.4064)
			(end -0.7874 -0.4064)
			(stroke
				(width 0.1524)
				(type default)
			)
			(layer "F.SilkS")
		)
		(fp_line
			(start 0.7874 -0.4064)
			(end 0.7874 0.4064)
			(stroke
				(width 0.1524)
				(type default)
			)
			(layer "F.SilkS")
		)
		(fp_line
			(start 0.7874 0.4064)
			(end -0.7874 0.4064)
			(stroke
				(width 0.1524)
				(type default)
			)
			(layer "F.SilkS")
		)
		(fp_line
			(start -0.67945 -0.305054)
			(end -0.12065 -0.305054)
			(stroke
				(width 0.1)
				(type default)
			)
			(layer "F.Fab")
		)
		(fp_line
			(start -0.67945 0.3048)
			(end -0.67945 -0.305054)
			(stroke
				(width 0.1)
				(type default)
			)
			(layer "F.Fab")
		)
		(fp_line
			(start -0.12065 -0.305054)
			(end -0.12065 -0.2794)
			(stroke
				(width 0.1)
				(type default)
			)
			(layer "F.Fab")
		)
		(fp_line
			(start -0.12065 -0.2794)
			(end 0.12065 -0.2794)
			(stroke
				(width 0.1)
				(type default)
			)
			(layer "F.Fab")
		)
		(fp_line
			(start -0.12065 0.2794)
			(end -0.12065 0.3048)
			(stroke
				(width 0.1)
				(type default)
			)
			(layer "F.Fab")
		)
		(fp_line
			(start -0.12065 0.3048)
			(end -0.67945 0.3048)
			(stroke
				(width 0.1)
				(type default)
			)
			(layer "F.Fab")
		)
		(fp_line
			(start 0.120396 0.2794)
			(end -0.12065 0.2794)
			(stroke
				(width 0.1)
				(type default)
			)
			(layer "F.Fab")
		)
		(fp_line
			(start 0.120396 0.3048)
			(end 0.120396 0.2794)
			(stroke
				(width 0.1)
				(type default)
			)
			(layer "F.Fab")
		)
		(fp_line
			(start 0.12065 -0.3048)
			(end 0.67945 -0.3048)
			(stroke
				(width 0.1)
				(type default)
			)
			(layer "F.Fab")
		)
		(fp_line
			(start 0.12065 -0.2794)
			(end 0.12065 -0.3048)
			(stroke
				(width 0.1)
				(type default)
			)
			(layer "F.Fab")
		)
		(fp_line
			(start 0.67945 -0.3048)
			(end 0.67945 0.3048)
			(stroke
				(width 0.1)
				(type default)
			)
			(layer "F.Fab")
		)
		(fp_line
			(start 0.67945 0.3048)
			(end 0.120396 0.3048)
			(stroke
				(width 0.1)
				(type default)
			)
			(layer "F.Fab")
		)
		(pad "1" smd circle
			(at -0.40005 0)
			(size 0 0)
			(layers "F.Cu" "F.Mask" "F.Paste")
			(net "GND")
		)
		(pad "2" smd circle
			(at 0.40005 0)
			(size 0 0)
			(layers "F.Cu" "F.Mask" "F.Paste")
			(net "P12V_SCM_REG")
		)
	)
	(footprint ""
		(layer "F.Cu")
		(at 357.587042 -392.04265 180)
		(property "Reference" "C2272"
			(at 0 0 180)
			(layer "F.SilkS")
			(hide yes)
			(effects
				(font
					(size 1.27 1.27)
				)
			)
		)
		(property "Value" ""
			(at 0 0 180)
			(layer "F.Fab")
			(effects
				(font
					(size 1.27 1.27)
				)
			)
		)
		(duplicate_pad_numbers_are_jumpers no)
		(fp_line
			(start 0.7874 0.4064)
			(end -0.7874 0.4064)
			(stroke
				(width 0.1524)
				(type default)
			)
			(layer "F.SilkS")
		)
		(fp_line
			(start 0.7874 -0.4064)
			(end 0.7874 0.4064)
			(stroke
				(width 0.1524)
				(type default)
			)
			(layer "F.SilkS")
		)
		(fp_line
			(start -0.7874 0.4064)
			(end -0.7874 -0.4064)
			(stroke
				(width 0.1524)
				(type default)
			)
			(layer "F.SilkS")
		)
		(fp_line
			(start -0.7874 -0.4064)
			(end 0.7874 -0.4064)
			(stroke
				(width 0.1524)
				(type default)
			)
			(layer "F.SilkS")
		)
		(fp_line
			(start 0.67945 0.3048)
			(end 0.120396 0.3048)
			(stroke
				(width 0.1)
				(type default)
			)
			(layer "F.Fab")
		)
		(fp_line
			(start 0.67945 -0.3048)
			(end 0.67945 0.3048)
			(stroke
				(width 0.1)
				(type default)
			)
			(layer "F.Fab")
		)
		(fp_line
			(start 0.12065 -0.2794)
			(end 0.12065 -0.3048)
			(stroke
				(width 0.1)
				(type default)
			)
			(layer "F.Fab")
		)
		(fp_line
			(start 0.12065 -0.3048)
			(end 0.67945 -0.3048)
			(stroke
				(width 0.1)
				(type default)
			)
			(layer "F.Fab")
		)
		(fp_line
			(start 0.120396 0.3048)
			(end 0.120396 0.2794)
			(stroke
				(width 0.1)
				(type default)
			)
			(layer "F.Fab")
		)
		(fp_line
			(start 0.120396 0.2794)
			(end -0.12065 0.2794)
			(stroke
				(width 0.1)
				(type default)
			)
			(layer "F.Fab")
		)
		(fp_line
			(start -0.12065 0.3048)
			(end -0.67945 0.3048)
			(stroke
				(width 0.1)
				(type default)
			)
			(layer "F.Fab")
		)
		(fp_line
			(start -0.12065 0.2794)
			(end -0.12065 0.3048)
			(stroke
				(width 0.1)
				(type default)
			)
			(layer "F.Fab")
		)
		(fp_line
			(start -0.12065 -0.2794)
			(end 0.12065 -0.2794)
			(stroke
				(width 0.1)
				(type default)
			)
			(layer "F.Fab")
		)
		(fp_line
			(start -0.12065 -0.305054)
			(end -0.12065 -0.2794)
			(stroke
				(width 0.1)
				(type default)
			)
			(layer "F.Fab")
		)
		(fp_line
			(start -0.67945 0.3048)
			(end -0.67945 -0.305054)
			(stroke
				(width 0.1)
				(type default)
			)
			(layer "F.Fab")
		)
		(fp_line
			(start -0.67945 -0.305054)
			(end -0.12065 -0.305054)
			(stroke
				(width 0.1)
				(type default)
			)
			(layer "F.Fab")
		)
		(pad "1" smd circle
			(at -0.40005 0 180)
			(size 0 0)
			(layers "F.Cu" "F.Mask" "F.Paste")
			(net "GPU_3V3IO_RSVD4_ISO")
		)
		(pad "2" smd circle
			(at 0.40005 0 180)
			(size 0 0)
			(layers "F.Cu" "F.Mask" "F.Paste")
			(net "GND")
		)
	)
	(footprint ""
		(layer "F.Cu")
		(at 182.82158 -411.20568 -90)
		(property "Reference" "C2389"
			(at 0 0 270)
			(layer "F.SilkS")
			(hide yes)
			(effects
				(font
					(size 1.27 1.27)
				)
			)
		)
		(property "Value" ""
			(at 0 0 270)
			(layer "F.Fab")
			(effects
				(font
					(size 1.27 1.27)
				)
			)
		)
		(duplicate_pad_numbers_are_jumpers no)
		(fp_line
			(start -0.7874 0.4064)
			(end -0.7874 -0.4064)
			(stroke
				(width 0.1524)
				(type default)
			)
			(layer "F.SilkS")
		)
		(fp_line
			(start 0.7874 0.4064)
			(end -0.7874 0.4064)
			(stroke
				(width 0.1524)
				(type default)
			)
			(layer "F.SilkS")
		)
		(fp_line
			(start -0.7874 -0.4064)
			(end 0.7874 -0.4064)
			(stroke
				(width 0.1524)
				(type default)
			)
			(layer "F.SilkS")
		)
		(fp_line
			(start 0.7874 -0.4064)
			(end 0.7874 0.4064)
			(stroke
				(width 0.1524)
				(type default)
			)
			(layer "F.SilkS")
		)
		(fp_line
			(start -0.67945 0.3048)
			(end -0.67945 -0.305054)
			(stroke
				(width 0.1)
				(type default)
			)
			(layer "F.Fab")
		)
		(fp_line
			(start -0.12065 0.3048)
			(end -0.67945 0.3048)
			(stroke
				(width 0.1)
				(type default)
			)
			(layer "F.Fab")
		)
		(fp_line
			(start 0.120396 0.3048)
			(end 0.120396 0.2794)
			(stroke
				(width 0.1)
				(type default)
			)
			(layer "F.Fab")
		)
		(fp_line
			(start 0.67945 0.3048)
			(end 0.120396 0.3048)
			(stroke
				(width 0.1)
				(type default)
			)
			(layer "F.Fab")
		)
		(fp_line
			(start -0.12065 0.2794)
			(end -0.12065 0.3048)
			(stroke
				(width 0.1)
				(type default)
			)
			(layer "F.Fab")
		)
		(fp_line
			(start 0.120396 0.2794)
			(end -0.12065 0.2794)
			(stroke
				(width 0.1)
				(type default)
			)
			(layer "F.Fab")
		)
		(fp_line
			(start -0.12065 -0.2794)
			(end 0.12065 -0.2794)
			(stroke
				(width 0.1)
				(type default)
			)
			(layer "F.Fab")
		)
		(fp_line
			(start 0.12065 -0.2794)
			(end 0.12065 -0.3048)
			(stroke
				(width 0.1)
				(type default)
			)
			(layer "F.Fab")
		)
		(fp_line
			(start 0.12065 -0.3048)
			(end 0.67945 -0.3048)
			(stroke
				(width 0.1)
				(type default)
			)
			(layer "F.Fab")
		)
		(fp_line
			(start 0.67945 -0.3048)
			(end 0.67945 0.3048)
			(stroke
				(width 0.1)
				(type default)
			)
			(layer "F.Fab")
		)
		(fp_line
			(start -0.67945 -0.305054)
			(end -0.12065 -0.305054)
			(stroke
				(width 0.1)
				(type default)
			)
			(layer "F.Fab")
		)
		(fp_line
			(start -0.12065 -0.305054)
			(end -0.12065 -0.2794)
			(stroke
				(width 0.1)
				(type default)
			)
			(layer "F.Fab")
		)
		(pad "1" smd circle
			(at -0.40005 0 270)
			(size 0 0)
			(layers "F.Cu" "F.Mask" "F.Paste")
			(net "HSC_OC_VOL")
		)
		(pad "2" smd circle
			(at 0.40005 0 270)
			(size 0 0)
			(layers "F.Cu" "F.Mask" "F.Paste")
			(net "GND")
		)
	)
	(footprint ""
		(layer "F.Cu")
		(at 256.473452 -92.292424)
		(property "Reference" "R3641"
			(at 0 0 0)
			(layer "F.SilkS")
			(hide yes)
			(effects
				(font
					(size 1.27 1.27)
				)
			)
		)
		(property "Value" ""
			(at 0 0 0)
			(layer "F.Fab")
			(effects
				(font
					(size 1.27 1.27)
				)
			)
		)
		(duplicate_pad_numbers_are_jumpers no)
		(fp_line
			(start -0.7874 -0.4064)
			(end 0.7874 -0.4064)
			(stroke
				(width 0.1524)
				(type default)
			)
			(layer "F.SilkS")
		)
		(fp_line
			(start -0.7874 0.4064)
			(end -0.7874 -0.4064)
			(stroke
				(width 0.1524)
				(type default)
			)
			(layer "F.SilkS")
		)
		(fp_line
			(start 0.7874 -0.4064)
			(end 0.7874 0.4064)
			(stroke
				(width 0.1524)
				(type default)
			)
			(layer "F.SilkS")
		)
		(fp_line
			(start 0.7874 0.4064)
			(end -0.7874 0.4064)
			(stroke
				(width 0.1524)
				(type default)
			)
			(layer "F.SilkS")
		)
		(fp_line
			(start -0.67945 -0.305054)
			(end -0.12065 -0.305054)
			(stroke
				(width 0.1)
				(type default)
			)
			(layer "F.Fab")
		)
		(fp_line
			(start -0.67945 0.3048)
			(end -0.67945 -0.305054)
			(stroke
				(width 0.1)
				(type default)
			)
			(layer "F.Fab")
		)
		(fp_line
			(start -0.12065 -0.305054)
			(end -0.12065 -0.2794)
			(stroke
				(width 0.1)
				(type default)
			)
			(layer "F.Fab")
		)
		(fp_line
			(start -0.12065 -0.2794)
			(end 0.12065 -0.2794)
			(stroke
				(width 0.1)
				(type default)
			)
			(layer "F.Fab")
		)
		(fp_line
			(start -0.12065 0.2794)
			(end -0.12065 0.3048)
			(stroke
				(width 0.1)
				(type default)
			)
			(layer "F.Fab")
		)
		(fp_line
			(start -0.12065 0.3048)
			(end -0.67945 0.3048)
			(stroke
				(width 0.1)
				(type default)
			)
			(layer "F.Fab")
		)
		(fp_line
			(start 0.120396 0.2794)
			(end -0.12065 0.2794)
			(stroke
				(width 0.1)
				(type default)
			)
			(layer "F.Fab")
		)
		(fp_line
			(start 0.120396 0.3048)
			(end 0.120396 0.2794)
			(stroke
				(width 0.1)
				(type default)
			)
			(layer "F.Fab")
		)
		(fp_line
			(start 0.12065 -0.3048)
			(end 0.67945 -0.3048)
			(stroke
				(width 0.1)
				(type default)
			)
			(layer "F.Fab")
		)
		(fp_line
			(start 0.12065 -0.2794)
			(end 0.12065 -0.3048)
			(stroke
				(width 0.1)
				(type default)
			)
			(layer "F.Fab")
		)
		(fp_line
			(start 0.67945 -0.3048)
			(end 0.67945 0.3048)
			(stroke
				(width 0.1)
				(type default)
			)
			(layer "F.Fab")
		)
		(fp_line
			(start 0.67945 0.3048)
			(end 0.120396 0.3048)
			(stroke
				(width 0.1)
				(type default)
			)
			(layer "F.Fab")
		)
		(pad "1" smd circle
			(at -0.40005 0)
			(size 0 0)
			(layers "F.Cu" "F.Mask" "F.Paste")
			(net "P3V3_AUX")
		)
		(pad "2" smd circle
			(at 0.40005 0)
			(size 0 0)
			(layers "F.Cu" "F.Mask" "F.Paste")
			(net "CK440Q_OE_4")
		)
	)
	(footprint ""
		(layer "F.Cu")
		(at 350.1517 -30.520894 -90)
		(property "Reference" "R496"
			(at 0 0 270)
			(layer "F.SilkS")
			(hide yes)
			(effects
				(font
					(size 1.27 1.27)
				)
			)
		)
		(property "Value" ""
			(at 0 0 270)
			(layer "F.Fab")
			(effects
				(font
					(size 1.27 1.27)
				)
			)
		)
		(duplicate_pad_numbers_are_jumpers no)
		(fp_line
			(start -0.7874 0.4064)
			(end -0.7874 -0.4064)
			(stroke
				(width 0.1524)
				(type default)
			)
			(layer "F.SilkS")
		)
		(fp_line
			(start 0.7874 0.4064)
			(end -0.7874 0.4064)
			(stroke
				(width 0.1524)
				(type default)
			)
			(layer "F.SilkS")
		)
		(fp_line
			(start -0.7874 -0.4064)
			(end 0.7874 -0.4064)
			(stroke
				(width 0.1524)
				(type default)
			)
			(layer "F.SilkS")
		)
		(fp_line
			(start 0.7874 -0.4064)
			(end 0.7874 0.4064)
			(stroke
				(width 0.1524)
				(type default)
			)
			(layer "F.SilkS")
		)
		(fp_line
			(start -0.67945 0.3048)
			(end -0.67945 -0.305054)
			(stroke
				(width 0.1)
				(type default)
			)
			(layer "F.Fab")
		)
		(fp_line
			(start -0.12065 0.3048)
			(end -0.67945 0.3048)
			(stroke
				(width 0.1)
				(type default)
			)
			(layer "F.Fab")
		)
		(fp_line
			(start 0.120396 0.3048)
			(end 0.120396 0.2794)
			(stroke
				(width 0.1)
				(type default)
			)
			(layer "F.Fab")
		)
		(fp_line
			(start 0.67945 0.3048)
			(end 0.120396 0.3048)
			(stroke
				(width 0.1)
				(type default)
			)
			(layer "F.Fab")
		)
		(fp_line
			(start -0.12065 0.2794)
			(end -0.12065 0.3048)
			(stroke
				(width 0.1)
				(type default)
			)
			(layer "F.Fab")
		)
		(fp_line
			(start 0.120396 0.2794)
			(end -0.12065 0.2794)
			(stroke
				(width 0.1)
				(type default)
			)
			(layer "F.Fab")
		)
		(fp_line
			(start -0.12065 -0.2794)
			(end 0.12065 -0.2794)
			(stroke
				(width 0.1)
				(type default)
			)
			(layer "F.Fab")
		)
		(fp_line
			(start 0.12065 -0.2794)
			(end 0.12065 -0.3048)
			(stroke
				(width 0.1)
				(type default)
			)
			(layer "F.Fab")
		)
		(fp_line
			(start 0.12065 -0.3048)
			(end 0.67945 -0.3048)
			(stroke
				(width 0.1)
				(type default)
			)
			(layer "F.Fab")
		)
		(fp_line
			(start 0.67945 -0.3048)
			(end 0.67945 0.3048)
			(stroke
				(width 0.1)
				(type default)
			)
			(layer "F.Fab")
		)
		(fp_line
			(start -0.67945 -0.305054)
			(end -0.12065 -0.305054)
			(stroke
				(width 0.1)
				(type default)
			)
			(layer "F.Fab")
		)
		(fp_line
			(start -0.12065 -0.305054)
			(end -0.12065 -0.2794)
			(stroke
				(width 0.1)
				(type default)
			)
			(layer "F.Fab")
		)
		(pad "1" smd circle
			(at -0.40005 0 270)
			(size 0 0)
			(layers "F.Cu" "F.Mask" "F.Paste")
			(net "PD_PCH_USB2_COMP")
		)
		(pad "2" smd circle
			(at 0.40005 0 270)
			(size 0 0)
			(layers "F.Cu" "F.Mask" "F.Paste")
			(net "GND")
		)
	)
)
